# T6G (Grand Teton) — schematic netlist excerpt (pin names and nets, part order shuffled) for the footprints in the layout excerpt that follows; sources: Cadence DE-HDL packaged netlist, KiCad conversion of 04192023_DAF0TMB3IC0_F0TG_MB_C_brd_V02_OCP.brd

R1349  Q_RES  33.2 1% CHIP  pkg 0402LF  page 251 : A = SMB_INA230_3V3AUX_SDA ; B = SMB_INA230_8_3V3AUX_SDA_R

(kicad_pcb
	(version 20260206)
	(generator "pcbnew")
	(generator_version "10.0")
	(general
		(thickness 1.6)
		(legacy_teardrops no)
	)
	(paper "A4")
	(title_block
		(title "04192023_DAF0TMB3IC0_F0TG_MB_C_brd_V02_OCP.brd")
		(comment 1 "Grand Teton / footprints 1935-1935 of 8354")
	)
	(layers
		(0 "F.Cu" signal "TOP")
		(4 "In1.Cu" signal "GND")
		(6 "In2.Cu" signal "IN1")
		(8 "In3.Cu" signal "GND1")
		(10 "In4.Cu" signal "IN2")
		(12 "In5.Cu" signal "GND2")
		(14 "In6.Cu" signal "IN3")
		(16 "In7.Cu" signal "GND3")
		(18 "In8.Cu" signal "VCC")
		(20 "In9.Cu" signal "VCC1")
		(22 "In10.Cu" signal "GND4")
		(24 "In11.Cu" signal "IN4")
		(26 "In12.Cu" signal "GND5")
		(28 "In13.Cu" signal "IN5")
		(30 "In14.Cu" signal "GND6")
		(32 "In15.Cu" signal "IN6")
		(34 "In16.Cu" signal "GND7")
		(2 "B.Cu" signal "BOTTOM")
		(9 "F.Adhes" user "F.Adhesive")
		(11 "B.Adhes" user "B.Adhesive")
		(13 "F.Paste" user "Package Geometry/Pastemask Top")
		(15 "B.Paste" user "Package Geometry/Pastemask Bottom")
		(5 "F.SilkS" user "Ref Des/Silkscreen Top")
		(7 "B.SilkS" user "Ref Des/Silkscreen Bottom")
		(1 "F.Mask" user "Board Geometry/Soldermask Top")
		(3 "B.Mask" user "Board Geometry/Soldermask Bottom")
		(17 "Dwgs.User" user "User.Drawings")
		(19 "Cmts.User" user "User.Comments")
		(21 "Eco1.User" user "User.Eco1")
		(23 "Eco2.User" user "User.Eco2")
		(25 "Edge.Cuts" user "Board Geometry/Outline")
		(27 "Margin" user)
		(31 "F.CrtYd" user "Package Geometry/Place Bound Top")
		(29 "B.CrtYd" user "Package Geometry/Place Bound Bottom")
		(35 "F.Fab" user "Ref Des/Assembly Top")
		(33 "B.Fab" user "Ref Des/Assembly Bottom")
	)
	(footprint ""
		(layer "F.Cu")
		(at 300.736 -108.56595 -90)
		(property "Reference" "R1349"
			(at 0 0 270)
			(layer "F.SilkS")
			(hide yes)
			(effects
				(font
					(size 1.27 1.27)
				)
			)
		)
		(property "Value" ""
			(at 0 0 270)
			(layer "F.Fab")
			(effects
				(font
					(size 1.27 1.27)
				)
			)
		)
		(duplicate_pad_numbers_are_jumpers no)
		(fp_line
			(start -0.7874 0.4064)
			(end -0.7874 -0.4064)
			(stroke
				(width 0.1524)
				(type default)
			)
			(layer "F.SilkS")
		)
		(fp_line
			(start 0.7874 0.4064)
			(end -0.7874 0.4064)
			(stroke
				(width 0.1524)
				(type default)
			)
			(layer "F.SilkS")
		)
		(fp_line
			(start -0.7874 -0.4064)
			(end 0.7874 -0.4064)
			(stroke
				(width 0.1524)
				(type default)
			)
			(layer "F.SilkS")
		)
		(fp_line
			(start 0.7874 -0.4064)
			(end 0.7874 0.4064)
			(stroke
				(width 0.1524)
				(type default)
			)
			(layer "F.SilkS")
		)
		(fp_line
			(start -0.67945 0.3048)
			(end -0.67945 -0.305054)
			(stroke
				(width 0.1)
				(type default)
			)
			(layer "F.Fab")
		)
		(fp_line
			(start -0.12065 0.3048)
			(end -0.67945 0.3048)
			(stroke
				(width 0.1)
				(type default)
			)
			(layer "F.Fab")
		)
		(fp_line
			(start 0.120396 0.3048)
			(end 0.120396 0.2794)
			(stroke
				(width 0.1)
				(type default)
			)
			(layer "F.Fab")
		)
		(fp_line
			(start 0.67945 0.3048)
			(end 0.120396 0.3048)
			(stroke
				(width 0.1)
				(type default)
			)
			(layer "F.Fab")
		)
		(fp_line
			(start -0.12065 0.2794)
			(end -0.12065 0.3048)
			(stroke
				(width 0.1)
				(type default)
			)
			(layer "F.Fab")
		)
		(fp_line
			(start 0.120396 0.2794)
			(end -0.12065 0.2794)
			(stroke
				(width 0.1)
				(type default)
			)
			(layer "F.Fab")
		)
		(fp_line
			(start -0.12065 -0.2794)
			(end 0.12065 -0.2794)
			(stroke
				(width 0.1)
				(type default)
			)
			(layer "F.Fab")
		)
		(fp_line
			(start 0.12065 -0.2794)
			(end 0.12065 -0.3048)
			(stroke
				(width 0.1)
				(type default)
			)
			(layer "F.Fab")
		)
		(fp_line
			(start 0.12065 -0.3048)
			(end 0.67945 -0.3048)
			(stroke
				(width 0.1)
				(type default)
			)
			(layer "F.Fab")
		)
		(fp_line
			(start 0.67945 -0.3048)
			(end 0.67945 0.3048)
			(stroke
				(width 0.1)
				(type default)
			)
			(layer "F.Fab")
		)
		(fp_line
			(start -0.67945 -0.305054)
			(end -0.12065 -0.305054)
			(stroke
				(width 0.1)
				(type default)
			)
			(layer "F.Fab")
		)
		(fp_line
			(start -0.12065 -0.305054)
			(end -0.12065 -0.2794)
			(stroke
				(width 0.1)
				(type default)
			)
			(layer "F.Fab")
		)
		(pad "1" smd circle
			(at -0.40005 0 270)
			(size 0 0)
			(layers "F.Cu" "F.Mask" "F.Paste")
			(net "SMB_INA230_3V3AUX_SDA")
		)
		(pad "2" smd circle
			(at 0.40005 0 270)
			(size 0 0)
			(layers "F.Cu" "F.Mask" "F.Paste")
			(net "SMB_INA230_8_3V3AUX_SDA_R")
		)
	)
)
